# S9S_MB_2U (Grand Teton) — schematic netlist excerpt (pin names and nets, part order shuffled) for the footprints in the layout excerpt that follows; sources: Cadence DE-HDL packaged netlist, KiCad conversion of 03242023_DA0F0TMBIJ0_F0T_Motherboard_J_brd_V01_OCP.brd

R2933  Q_RES  4.7K 5% CHIP  pkg 0402LF  page 148 : A = P3V3_AUX ; B = FM_SWB_BIC_READY_ISO_N
PC442_P1_1  Q_CAP  3300PF 50V 10% X7R  pkg 0402  page 293 : A = SW_P12V_PVCCINFAON_CPU1_FLT ; B = GND

(kicad_pcb
	(version 20260206)
	(generator "pcbnew")
	(generator_version "10.0")
	(general
		(thickness 1.6)
		(legacy_teardrops no)
	)
	(paper "A4")
	(title_block
		(title "03242023_DA0F0TMBIJ0_F0T_Motherboard_J_brd_V01_OCP.brd")
		(comment 1 "Grand Teton / footprints 1873-1874 of 6105")
	)
	(layers
		(0 "F.Cu" signal "TOP")
		(4 "In1.Cu" signal "GND")
		(6 "In2.Cu" signal "IN1")
		(8 "In3.Cu" signal "GND1")
		(10 "In4.Cu" signal "IN2")
		(12 "In5.Cu" signal "GND2")
		(14 "In6.Cu" signal "IN3")
		(16 "In7.Cu" signal "GND3")
		(18 "In8.Cu" signal "VCC")
		(20 "In9.Cu" signal "VCC1")
		(22 "In10.Cu" signal "GND4")
		(24 "In11.Cu" signal "IN4")
		(26 "In12.Cu" signal "GND5")
		(28 "In13.Cu" signal "IN5")
		(30 "In14.Cu" signal "GND6")
		(32 "In15.Cu" signal "IN6")
		(34 "In16.Cu" signal "GND7")
		(2 "B.Cu" signal "BOTTOM")
		(9 "F.Adhes" user "F.Adhesive")
		(11 "B.Adhes" user "B.Adhesive")
		(13 "F.Paste" user "Package Geometry/Pastemask Top")
		(15 "B.Paste" user "Package Geometry/Pastemask Bottom")
		(5 "F.SilkS" user "Ref Des/Silkscreen Top")
		(7 "B.SilkS" user "Ref Des/Silkscreen Bottom")
		(1 "F.Mask" user "Board Geometry/Soldermask Top")
		(3 "B.Mask" user "Board Geometry/Soldermask Bottom")
		(17 "Dwgs.User" user "User.Drawings")
		(19 "Cmts.User" user "User.Comments")
		(21 "Eco1.User" user "User.Eco1")
		(23 "Eco2.User" user "User.Eco2")
		(25 "Edge.Cuts" user "Board Geometry/Outline")
		(27 "Margin" user)
		(31 "F.CrtYd" user "Package Geometry/Place Bound Top")
		(29 "B.CrtYd" user "Package Geometry/Place Bound Bottom")
		(35 "F.Fab" user "Ref Des/Assembly Top")
		(33 "B.Fab" user "Ref Des/Assembly Bottom")
	)
	(footprint ""
		(layer "F.Cu")
		(at 424.204892 -389.600948)
		(property "Reference" "R2933"
			(at 0 0 0)
			(layer "F.SilkS")
			(hide yes)
			(effects
				(font
					(size 1.27 1.27)
				)
			)
		)
		(property "Value" ""
			(at 0 0 0)
			(layer "F.Fab")
			(effects
				(font
					(size 1.27 1.27)
				)
			)
		)
		(duplicate_pad_numbers_are_jumpers no)
		(fp_line
			(start -0.7874 -0.4064)
			(end 0.7874 -0.4064)
			(stroke
				(width 0.1524)
				(type default)
			)
			(layer "F.SilkS")
		)
		(fp_line
			(start -0.7874 0.4064)
			(end -0.7874 -0.4064)
			(stroke
				(width 0.1524)
				(type default)
			)
			(layer "F.SilkS")
		)
		(fp_line
			(start 0.7874 -0.4064)
			(end 0.7874 0.4064)
			(stroke
				(width 0.1524)
				(type default)
			)
			(layer "F.SilkS")
		)
		(fp_line
			(start 0.7874 0.4064)
			(end -0.7874 0.4064)
			(stroke
				(width 0.1524)
				(type default)
			)
			(layer "F.SilkS")
		)
		(fp_line
			(start -0.67945 -0.305054)
			(end -0.12065 -0.305054)
			(stroke
				(width 0.1)
				(type default)
			)
			(layer "F.Fab")
		)
		(fp_line
			(start -0.67945 0.3048)
			(end -0.67945 -0.305054)
			(stroke
				(width 0.1)
				(type default)
			)
			(layer "F.Fab")
		)
		(fp_line
			(start -0.12065 -0.305054)
			(end -0.12065 -0.2794)
			(stroke
				(width 0.1)
				(type default)
			)
			(layer "F.Fab")
		)
		(fp_line
			(start -0.12065 -0.2794)
			(end 0.12065 -0.2794)
			(stroke
				(width 0.1)
				(type default)
			)
			(layer "F.Fab")
		)
		(fp_line
			(start -0.12065 0.2794)
			(end -0.12065 0.3048)
			(stroke
				(width 0.1)
				(type default)
			)
			(layer "F.Fab")
		)
		(fp_line
			(start -0.12065 0.3048)
			(end -0.67945 0.3048)
			(stroke
				(width 0.1)
				(type default)
			)
			(layer "F.Fab")
		)
		(fp_line
			(start 0.120396 0.2794)
			(end -0.12065 0.2794)
			(stroke
				(width 0.1)
				(type default)
			)
			(layer "F.Fab")
		)
		(fp_line
			(start 0.120396 0.3048)
			(end 0.120396 0.2794)
			(stroke
				(width 0.1)
				(type default)
			)
			(layer "F.Fab")
		)
		(fp_line
			(start 0.12065 -0.3048)
			(end 0.67945 -0.3048)
			(stroke
				(width 0.1)
				(type default)
			)
			(layer "F.Fab")
		)
		(fp_line
			(start 0.12065 -0.2794)
			(end 0.12065 -0.3048)
			(stroke
				(width 0.1)
				(type default)
			)
			(layer "F.Fab")
		)
		(fp_line
			(start 0.67945 -0.3048)
			(end 0.67945 0.3048)
			(stroke
				(width 0.1)
				(type default)
			)
			(layer "F.Fab")
		)
		(fp_line
			(start 0.67945 0.3048)
			(end 0.120396 0.3048)
			(stroke
				(width 0.1)
				(type default)
			)
			(layer "F.Fab")
		)
		(pad "1" smd circle
			(at -0.40005 0)
			(size 0 0)
			(layers "F.Cu" "F.Mask" "F.Paste")
			(net "P3V3_AUX")
		)
		(pad "2" smd circle
			(at 0.40005 0)
			(size 0 0)
			(layers "F.Cu" "F.Mask" "F.Paste")
			(net "FM_SWB_BIC_READY_ISO_N")
		)
	)
	(footprint ""
		(layer "F.Cu")
		(at 50.785014 -160.800542 90)
		(property "Reference" "PC442_P1_1"
			(at 0 0 90)
			(layer "F.SilkS")
			(hide yes)
			(effects
				(font
					(size 1.27 1.27)
				)
			)
		)
		(property "Value" ""
			(at 0 0 90)
			(layer "F.Fab")
			(effects
				(font
					(size 1.27 1.27)
				)
			)
		)
		(duplicate_pad_numbers_are_jumpers no)
		(fp_line
			(start 0.7874 -0.4064)
			(end 0.7874 0.4064)
			(stroke
				(width 0.1524)
				(type default)
			)
			(layer "F.SilkS")
		)
		(fp_line
			(start -0.7874 -0.4064)
			(end 0.7874 -0.4064)
			(stroke
				(width 0.1524)
				(type default)
			)
			(layer "F.SilkS")
		)
		(fp_line
			(start 0.7874 0.4064)
			(end -0.7874 0.4064)
			(stroke
				(width 0.1524)
				(type default)
			)
			(layer "F.SilkS")
		)
		(fp_line
			(start -0.7874 0.4064)
			(end -0.7874 -0.4064)
			(stroke
				(width 0.1524)
				(type default)
			)
			(layer "F.SilkS")
		)
		(fp_line
			(start -0.12065 -0.305054)
			(end -0.12065 -0.2794)
			(stroke
				(width 0.1)
				(type default)
			)
			(layer "F.Fab")
		)
		(fp_line
			(start -0.67945 -0.305054)
			(end -0.12065 -0.305054)
			(stroke
				(width 0.1)
				(type default)
			)
			(layer "F.Fab")
		)
		(fp_line
			(start 0.67945 -0.3048)
			(end 0.67945 0.3048)
			(stroke
				(width 0.1)
				(type default)
			)
			(layer "F.Fab")
		)
		(fp_line
			(start 0.12065 -0.3048)
			(end 0.67945 -0.3048)
			(stroke
				(width 0.1)
				(type default)
			)
			(layer "F.Fab")
		)
		(fp_line
			(start 0.12065 -0.2794)
			(end 0.12065 -0.3048)
			(stroke
				(width 0.1)
				(type default)
			)
			(layer "F.Fab")
		)
		(fp_line
			(start -0.12065 -0.2794)
			(end 0.12065 -0.2794)
			(stroke
				(width 0.1)
				(type default)
			)
			(layer "F.Fab")
		)
		(fp_line
			(start 0.120396 0.2794)
			(end -0.12065 0.2794)
			(stroke
				(width 0.1)
				(type default)
			)
			(layer "F.Fab")
		)
		(fp_line
			(start -0.12065 0.2794)
			(end -0.12065 0.3048)
			(stroke
				(width 0.1)
				(type default)
			)
			(layer "F.Fab")
		)
		(fp_line
			(start 0.67945 0.3048)
			(end 0.120396 0.3048)
			(stroke
				(width 0.1)
				(type default)
			)
			(layer "F.Fab")
		)
		(fp_line
			(start 0.120396 0.3048)
			(end 0.120396 0.2794)
			(stroke
				(width 0.1)
				(type default)
			)
			(layer "F.Fab")
		)
		(fp_line
			(start -0.12065 0.3048)
			(end -0.67945 0.3048)
			(stroke
				(width 0.1)
				(type default)
			)
			(layer "F.Fab")
		)
		(fp_line
			(start -0.67945 0.3048)
			(end -0.67945 -0.305054)
			(stroke
				(width 0.1)
				(type default)
			)
			(layer "F.Fab")
		)
		(pad "1" smd circle
			(at -0.40005 0 90)
			(size 0 0)
			(layers "F.Cu" "F.Mask" "F.Paste")
			(net "SW_P12V_PVCCINFAON_CPU1_FLT")
		)
		(pad "2" smd circle
			(at 0.40005 0 90)
			(size 0 0)
			(layers "F.Cu" "F.Mask" "F.Paste")
			(net "GND")
		)
	)
)
